(kicad_pcb
	(version 20260206)
	(generator "pcbnew")
	(generator_version "10.0")
	(general
		(thickness 1.6)
		(legacy_teardrops no)
	)
	(paper "A4")
	(title_block
		(title "01162023_DA0F0TEBIF0_F0T_Expander_BD_F_brd_V02_OCP.brd")
		(comment 1 "Grand Teton / footprints 5618-5621 of 9728")
	)
	(layers
		(0 "F.Cu" signal "TOP")
		(4 "In1.Cu" signal "GND")
		(6 "In2.Cu" signal "VCC")
		(8 "In3.Cu" signal "VCC1")
		(10 "In4.Cu" signal "GND1")
		(12 "In5.Cu" signal "IN1")
		(14 "In6.Cu" signal "GND2")
		(16 "In7.Cu" signal "IN2")
		(18 "In8.Cu" signal "GND3")
		(20 "In9.Cu" signal "IN3")
		(22 "In10.Cu" signal "GND4")
		(24 "In11.Cu" signal "IN4")
		(26 "In12.Cu" signal "GND5")
		(28 "In13.Cu" signal "IN5")
		(30 "In14.Cu" signal "GND6")
		(32 "In15.Cu" signal "IN6")
		(34 "In16.Cu" signal "GND7")
		(2 "B.Cu" signal "BOTTOM")
		(9 "F.Adhes" user "F.Adhesive")
		(11 "B.Adhes" user "B.Adhesive")
		(13 "F.Paste" user "Package Geometry/Pastemask Top")
		(15 "B.Paste" user "Package Geometry/Pastemask Bottom")
		(5 "F.SilkS" user "Ref Des/Silkscreen Top")
		(7 "B.SilkS" user "Ref Des/Silkscreen Bottom")
		(1 "F.Mask" user "Board Geometry/Soldermask Top")
		(3 "B.Mask" user "Board Geometry/Soldermask Bottom")
		(17 "Dwgs.User" user "User.Drawings")
		(19 "Cmts.User" user "User.Comments")
		(21 "Eco1.User" user "User.Eco1")
		(23 "Eco2.User" user "User.Eco2")
		(25 "Edge.Cuts" user "Board Geometry/Outline")
		(27 "Margin" user)
		(31 "F.CrtYd" user "Package Geometry/Place Bound Top")
		(29 "B.CrtYd" user "Package Geometry/Place Bound Bottom")
		(35 "F.Fab" user "Ref Des/Assembly Top")
		(33 "B.Fab" user "Ref Des/Assembly Bottom")
	)
	(footprint ""
		(layer "F.Cu")
		(at 393.826746 -55.418228 90)
		(property "Reference" "PC418"
			(at 0 0 90)
			(layer "F.SilkS")
			(hide yes)
			(effects
				(font
					(size 1.27 1.27)
				)
			)
		)
		(property "Value" ""
			(at 0 0 90)
			(layer "F.Fab")
			(effects
				(font
					(size 1.27 1.27)
				)
			)
		)
		(duplicate_pad_numbers_are_jumpers no)
		(fp_line
			(start 0.7874 -0.4064)
			(end 0.7874 0.4064)
			(stroke
				(width 0.1524)
				(type default)
			)
			(layer "F.SilkS")
		)
		(fp_line
			(start -0.7874 -0.4064)
			(end 0.7874 -0.4064)
			(stroke
				(width 0.1524)
				(type default)
			)
			(layer "F.SilkS")
		)
		(fp_line
			(start 0.7874 0.4064)
			(end -0.7874 0.4064)
			(stroke
				(width 0.1524)
				(type default)
			)
			(layer "F.SilkS")
		)
		(fp_line
			(start -0.7874 0.4064)
			(end -0.7874 -0.4064)
			(stroke
				(width 0.1524)
				(type default)
			)
			(layer "F.SilkS")
		)
		(fp_line
			(start -0.12065 -0.305054)
			(end -0.12065 -0.2794)
			(stroke
				(width 0.1)
				(type default)
			)
			(layer "F.Fab")
		)
		(fp_line
			(start -0.67945 -0.305054)
			(end -0.12065 -0.305054)
			(stroke
				(width 0.1)
				(type default)
			)
			(layer "F.Fab")
		)
		(fp_line
			(start 0.67945 -0.3048)
			(end 0.67945 0.3048)
			(stroke
				(width 0.1)
				(type default)
			)
			(layer "F.Fab")
		)
		(fp_line
			(start 0.12065 -0.3048)
			(end 0.67945 -0.3048)
			(stroke
				(width 0.1)
				(type default)
			)
			(layer "F.Fab")
		)
		(fp_line
			(start 0.12065 -0.2794)
			(end 0.12065 -0.3048)
			(stroke
				(width 0.1)
				(type default)
			)
			(layer "F.Fab")
		)
		(fp_line
			(start -0.12065 -0.2794)
			(end 0.12065 -0.2794)
			(stroke
				(width 0.1)
				(type default)
			)
			(layer "F.Fab")
		)
		(fp_line
			(start 0.120396 0.2794)
			(end -0.12065 0.2794)
			(stroke
				(width 0.1)
				(type default)
			)
			(layer "F.Fab")
		)
		(fp_line
			(start -0.12065 0.2794)
			(end -0.12065 0.3048)
			(stroke
				(width 0.1)
				(type default)
			)
			(layer "F.Fab")
		)
		(fp_line
			(start 0.67945 0.3048)
			(end 0.120396 0.3048)
			(stroke
				(width 0.1)
				(type default)
			)
			(layer "F.Fab")
		)
		(fp_line
			(start 0.120396 0.3048)
			(end 0.120396 0.2794)
			(stroke
				(width 0.1)
				(type default)
			)
			(layer "F.Fab")
		)
		(fp_line
			(start -0.12065 0.3048)
			(end -0.67945 0.3048)
			(stroke
				(width 0.1)
				(type default)
			)
			(layer "F.Fab")
		)
		(fp_line
			(start -0.67945 0.3048)
			(end -0.67945 -0.305054)
			(stroke
				(width 0.1)
				(type default)
			)
			(layer "F.Fab")
		)
		(pad "1" smd circle
			(at -0.40005 0 90)
			(size 0 0)
			(layers "F.Cu" "F.Mask" "F.Paste")
			(net "P12V_SSD13_R")
		)
		(pad "2" smd circle
			(at 0.40005 0 90)
			(size 0 0)
			(layers "F.Cu" "F.Mask" "F.Paste")
			(net "GND")
		)
	)
	(footprint ""
		(layer "F.Cu")
		(at 106.441494 -293.5351 90)
		(property "Reference" "PL6"
			(at -4.298442 29.039566 90)
			(unlocked yes)
			(layer "F.SilkS")
			(effects
				(font
					(size 0.7874 0.5842)
					(thickness 0.1524)
				)
				(justify left)
			)
		)
		(property "Value" ""
			(at 0 0 90)
			(layer "F.Fab")
			(effects
				(font
					(size 1.27 1.27)
				)
			)
		)
		(duplicate_pad_numbers_are_jumpers no)
		(fp_line
			(start 4.800092 -3.199892)
			(end 4.800092 -1.6764)
			(stroke
				(width 0.1524)
				(type default)
			)
			(layer "F.SilkS")
		)
		(fp_line
			(start -4.800092 -3.199892)
			(end 4.800092 -3.199892)
			(stroke
				(width 0.1524)
				(type default)
			)
			(layer "F.SilkS")
		)
		(fp_line
			(start -4.800092 -1.6764)
			(end -4.800092 -3.199892)
			(stroke
				(width 0.1524)
				(type default)
			)
			(layer "F.SilkS")
		)
		(fp_line
			(start 4.800092 1.6764)
			(end 4.800092 3.199892)
			(stroke
				(width 0.1524)
				(type default)
			)
			(layer "F.SilkS")
		)
		(fp_line
			(start 4.800092 3.199892)
			(end -4.800092 3.199892)
			(stroke
				(width 0.1524)
				(type default)
			)
			(layer "F.SilkS")
		)
		(fp_line
			(start -4.800092 3.199892)
			(end -4.800092 1.6764)
			(stroke
				(width 0.1524)
				(type default)
			)
			(layer "F.SilkS")
		)
		(fp_line
			(start 4.800092 -3.199892)
			(end 4.800092 3.199892)
			(stroke
				(width 0.1)
				(type default)
			)
			(layer "F.Fab")
		)
		(fp_line
			(start -4.800092 -3.199892)
			(end 4.800092 -3.199892)
			(stroke
				(width 0.1)
				(type default)
			)
			(layer "F.Fab")
		)
		(fp_line
			(start 4.800092 3.199892)
			(end -4.800092 3.199892)
			(stroke
				(width 0.1)
				(type default)
			)
			(layer "F.Fab")
		)
		(fp_line
			(start -4.800092 3.199892)
			(end -4.800092 -3.199892)
			(stroke
				(width 0.1)
				(type default)
			)
			(layer "F.Fab")
		)
		(pad "1" smd rect
			(at -3.074924 0 180)
			(size 3.0988 3.3528)
			(layers "F.Cu" "F.Mask" "F.Paste")
			(net "SW_P0V8_PEX0_PH1")
		)
		(pad "2" smd rect
			(at 3.074924 0 180)
			(size 3.0988 3.3528)
			(layers "F.Cu" "F.Mask" "F.Paste")
			(net "P0V8_PEX0")
		)
	)
	(footprint ""
		(layer "F.Cu")
		(at 144.149318 -287.395412 -90)
		(property "Reference" "C3208"
			(at 0 0 270)
			(layer "F.SilkS")
			(hide yes)
			(effects
				(font
					(size 1.27 1.27)
				)
			)
		)
		(property "Value" ""
			(at 0 0 270)
			(layer "F.Fab")
			(effects
				(font
					(size 1.27 1.27)
				)
			)
		)
		(duplicate_pad_numbers_are_jumpers no)
		(fp_line
			(start -0.299974 0.150114)
			(end -0.299974 -0.150114)
			(stroke
				(width 0.1)
				(type default)
			)
			(layer "F.Fab")
		)
		(fp_line
			(start 0.299974 0.150114)
			(end -0.299974 0.150114)
			(stroke
				(width 0.1)
				(type default)
			)
			(layer "F.Fab")
		)
		(fp_line
			(start -0.299974 -0.150114)
			(end 0.299974 -0.150114)
			(stroke
				(width 0.1)
				(type default)
			)
			(layer "F.Fab")
		)
		(fp_line
			(start 0.299974 -0.150114)
			(end 0.299974 0.150114)
			(stroke
				(width 0.1)
				(type default)
			)
			(layer "F.Fab")
		)
		(pad "1" smd rect
			(at -0.2667 0 270)
			(size 0.3048 0.381)
			(layers "F.Cu" "F.Mask" "F.Paste")
			(net "P1V8_PLL0_PEX1")
		)
		(pad "2" smd rect
			(at 0.2667 0 270)
			(size 0.3048 0.381)
			(layers "F.Cu" "F.Mask" "F.Paste")
			(net "GND")
		)
	)
	(footprint ""
		(layer "F.Cu")
		(at 344.511884 -111.531654)
		(property "Reference" "PR7037"
			(at 0 0 0)
			(layer "F.SilkS")
			(hide yes)
			(effects
				(font
					(size 1.27 1.27)
				)
			)
		)
		(property "Value" ""
			(at 0 0 0)
			(layer "F.Fab")
			(effects
				(font
					(size 1.27 1.27)
				)
			)
		)
		(duplicate_pad_numbers_are_jumpers no)
		(fp_line
			(start -0.7874 -0.4064)
			(end 0.7874 -0.4064)
			(stroke
				(width 0.1524)
				(type default)
			)
			(layer "F.SilkS")
		)
		(fp_line
			(start -0.7874 0.4064)
			(end -0.7874 -0.4064)
			(stroke
				(width 0.1524)
				(type default)
			)
			(layer "F.SilkS")
		)
		(fp_line
			(start 0.7874 -0.4064)
			(end 0.7874 0.4064)
			(stroke
				(width 0.1524)
				(type default)
			)
			(layer "F.SilkS")
		)
		(fp_line
			(start 0.7874 0.4064)
			(end -0.7874 0.4064)
			(stroke
				(width 0.1524)
				(type default)
			)
			(layer "F.SilkS")
		)
		(fp_line
			(start -0.67945 -0.305054)
			(end -0.12065 -0.305054)
			(stroke
				(width 0.1)
				(type default)
			)
			(layer "F.Fab")
		)
		(fp_line
			(start -0.67945 0.3048)
			(end -0.67945 -0.305054)
			(stroke
				(width 0.1)
				(type default)
			)
			(layer "F.Fab")
		)
		(fp_line
			(start -0.12065 -0.305054)
			(end -0.12065 -0.2794)
			(stroke
				(width 0.1)
				(type default)
			)
			(layer "F.Fab")
		)
		(fp_line
			(start -0.12065 -0.2794)
			(end 0.12065 -0.2794)
			(stroke
				(width 0.1)
				(type default)
			)
			(layer "F.Fab")
		)
		(fp_line
			(start -0.12065 0.2794)
			(end -0.12065 0.3048)
			(stroke
				(width 0.1)
				(type default)
			)
			(layer "F.Fab")
		)
		(fp_line
			(start -0.12065 0.3048)
			(end -0.67945 0.3048)
			(stroke
				(width 0.1)
				(type default)
			)
			(layer "F.Fab")
		)
		(fp_line
			(start 0.120396 0.2794)
			(end -0.12065 0.2794)
			(stroke
				(width 0.1)
				(type default)
			)
			(layer "F.Fab")
		)
		(fp_line
			(start 0.120396 0.3048)
			(end 0.120396 0.2794)
			(stroke
				(width 0.1)
				(type default)
			)
			(layer "F.Fab")
		)
		(fp_line
			(start 0.12065 -0.3048)
			(end 0.67945 -0.3048)
			(stroke
				(width 0.1)
				(type default)
			)
			(layer "F.Fab")
		)
		(fp_line
			(start 0.12065 -0.2794)
			(end 0.12065 -0.3048)
			(stroke
				(width 0.1)
				(type default)
			)
			(layer "F.Fab")
		)
		(fp_line
			(start 0.67945 -0.3048)
			(end 0.67945 0.3048)
			(stroke
				(width 0.1)
				(type default)
			)
			(layer "F.Fab")
		)
		(fp_line
			(start 0.67945 0.3048)
			(end 0.120396 0.3048)
			(stroke
				(width 0.1)
				(type default)
			)
			(layer "F.Fab")
		)
		(pad "1" smd circle
			(at -0.40005 0)
			(size 0 0)
			(layers "F.Cu" "F.Mask" "F.Paste")
			(net "P12V_NIC5_CO_ISET")
		)
		(pad "2" smd circle
			(at 0.40005 0)
			(size 0 0)
			(layers "F.Cu" "F.Mask" "F.Paste")
			(net "GND")
		)
	)
)
